# T6G (Grand Teton) — schematic netlist excerpt (pin names and nets, part order shuffled) for the footprints in the layout excerpt that follows; sources: Cadence DE-HDL packaged netlist, KiCad conversion of 04192023_DAF0TMB3IC0_F0TG_MB_C_brd_V02_OCP.brd

PR3823  Q_RES  845 1% CHIP  pkg 0402LF  page 140 : A = P12V_OCP_SENSE_2 ; B = GND
R6215  Q_RES  10K 1% CHIP  pkg 0402LF  page 176 : A = P3V3_AUX ; B = USB_CPU0_HUB1_MODE_SEL0

(kicad_pcb
	(version 20260206)
	(generator "pcbnew")
	(generator_version "10.0")
	(general
		(thickness 1.6)
		(legacy_teardrops no)
	)
	(paper "A4")
	(title_block
		(title "04192023_DAF0TMB3IC0_F0TG_MB_C_brd_V02_OCP.brd")
		(comment 1 "Grand Teton / footprints 3840-3841 of 8354")
	)
	(layers
		(0 "F.Cu" signal "TOP")
		(4 "In1.Cu" signal "GND")
		(6 "In2.Cu" signal "IN1")
		(8 "In3.Cu" signal "GND1")
		(10 "In4.Cu" signal "IN2")
		(12 "In5.Cu" signal "GND2")
		(14 "In6.Cu" signal "IN3")
		(16 "In7.Cu" signal "GND3")
		(18 "In8.Cu" signal "VCC")
		(20 "In9.Cu" signal "VCC1")
		(22 "In10.Cu" signal "GND4")
		(24 "In11.Cu" signal "IN4")
		(26 "In12.Cu" signal "GND5")
		(28 "In13.Cu" signal "IN5")
		(30 "In14.Cu" signal "GND6")
		(32 "In15.Cu" signal "IN6")
		(34 "In16.Cu" signal "GND7")
		(2 "B.Cu" signal "BOTTOM")
		(9 "F.Adhes" user "F.Adhesive")
		(11 "B.Adhes" user "B.Adhesive")
		(13 "F.Paste" user "Package Geometry/Pastemask Top")
		(15 "B.Paste" user "Package Geometry/Pastemask Bottom")
		(5 "F.SilkS" user "Ref Des/Silkscreen Top")
		(7 "B.SilkS" user "Ref Des/Silkscreen Bottom")
		(1 "F.Mask" user "Board Geometry/Soldermask Top")
		(3 "B.Mask" user "Board Geometry/Soldermask Bottom")
		(17 "Dwgs.User" user "User.Drawings")
		(19 "Cmts.User" user "User.Comments")
		(21 "Eco1.User" user "User.Eco1")
		(23 "Eco2.User" user "User.Eco2")
		(25 "Edge.Cuts" user "Board Geometry/Outline")
		(27 "Margin" user)
		(31 "F.CrtYd" user "Package Geometry/Place Bound Top")
		(29 "B.CrtYd" user "Package Geometry/Place Bound Bottom")
		(35 "F.Fab" user "Ref Des/Assembly Top")
		(33 "B.Fab" user "Ref Des/Assembly Bottom")
	)
	(footprint ""
		(layer "F.Cu")
		(at 137.971784 -50.611024 180)
		(property "Reference" "R6215"
			(at 0 0 180)
			(layer "F.SilkS")
			(hide yes)
			(effects
				(font
					(size 1.27 1.27)
				)
			)
		)
		(property "Value" ""
			(at 0 0 180)
			(layer "F.Fab")
			(effects
				(font
					(size 1.27 1.27)
				)
			)
		)
		(duplicate_pad_numbers_are_jumpers no)
		(fp_line
			(start 0.7874 0.4064)
			(end -0.7874 0.4064)
			(stroke
				(width 0.1524)
				(type default)
			)
			(layer "F.SilkS")
		)
		(fp_line
			(start 0.7874 -0.4064)
			(end 0.7874 0.4064)
			(stroke
				(width 0.1524)
				(type default)
			)
			(layer "F.SilkS")
		)
		(fp_line
			(start -0.7874 0.4064)
			(end -0.7874 -0.4064)
			(stroke
				(width 0.1524)
				(type default)
			)
			(layer "F.SilkS")
		)
		(fp_line
			(start -0.7874 -0.4064)
			(end 0.7874 -0.4064)
			(stroke
				(width 0.1524)
				(type default)
			)
			(layer "F.SilkS")
		)
		(fp_line
			(start 0.67945 0.3048)
			(end 0.120396 0.3048)
			(stroke
				(width 0.1)
				(type default)
			)
			(layer "F.Fab")
		)
		(fp_line
			(start 0.67945 -0.3048)
			(end 0.67945 0.3048)
			(stroke
				(width 0.1)
				(type default)
			)
			(layer "F.Fab")
		)
		(fp_line
			(start 0.12065 -0.2794)
			(end 0.12065 -0.3048)
			(stroke
				(width 0.1)
				(type default)
			)
			(layer "F.Fab")
		)
		(fp_line
			(start 0.12065 -0.3048)
			(end 0.67945 -0.3048)
			(stroke
				(width 0.1)
				(type default)
			)
			(layer "F.Fab")
		)
		(fp_line
			(start 0.120396 0.3048)
			(end 0.120396 0.2794)
			(stroke
				(width 0.1)
				(type default)
			)
			(layer "F.Fab")
		)
		(fp_line
			(start 0.120396 0.2794)
			(end -0.12065 0.2794)
			(stroke
				(width 0.1)
				(type default)
			)
			(layer "F.Fab")
		)
		(fp_line
			(start -0.12065 0.3048)
			(end -0.67945 0.3048)
			(stroke
				(width 0.1)
				(type default)
			)
			(layer "F.Fab")
		)
		(fp_line
			(start -0.12065 0.2794)
			(end -0.12065 0.3048)
			(stroke
				(width 0.1)
				(type default)
			)
			(layer "F.Fab")
		)
		(fp_line
			(start -0.12065 -0.2794)
			(end 0.12065 -0.2794)
			(stroke
				(width 0.1)
				(type default)
			)
			(layer "F.Fab")
		)
		(fp_line
			(start -0.12065 -0.305054)
			(end -0.12065 -0.2794)
			(stroke
				(width 0.1)
				(type default)
			)
			(layer "F.Fab")
		)
		(fp_line
			(start -0.67945 0.3048)
			(end -0.67945 -0.305054)
			(stroke
				(width 0.1)
				(type default)
			)
			(layer "F.Fab")
		)
		(fp_line
			(start -0.67945 -0.305054)
			(end -0.12065 -0.305054)
			(stroke
				(width 0.1)
				(type default)
			)
			(layer "F.Fab")
		)
		(pad "1" smd circle
			(at -0.40005 0 180)
			(size 0 0)
			(layers "F.Cu" "F.Mask" "F.Paste")
			(net "P3V3_AUX")
		)
		(pad "2" smd circle
			(at 0.40005 0 180)
			(size 0 0)
			(layers "F.Cu" "F.Mask" "F.Paste")
			(net "USB_CPU0_HUB1_MODE_SEL0")
		)
	)
	(footprint ""
		(layer "F.Cu")
		(at 75.546458 -21.839682 180)
		(property "Reference" "PR3823"
			(at 0 0 180)
			(layer "F.SilkS")
			(hide yes)
			(effects
				(font
					(size 1.27 1.27)
				)
			)
		)
		(property "Value" ""
			(at 0 0 180)
			(layer "F.Fab")
			(effects
				(font
					(size 1.27 1.27)
				)
			)
		)
		(duplicate_pad_numbers_are_jumpers no)
		(fp_line
			(start 0.7874 0.4064)
			(end -0.7874 0.4064)
			(stroke
				(width 0.1524)
				(type default)
			)
			(layer "F.SilkS")
		)
		(fp_line
			(start 0.7874 -0.4064)
			(end 0.7874 0.4064)
			(stroke
				(width 0.1524)
				(type default)
			)
			(layer "F.SilkS")
		)
		(fp_line
			(start -0.7874 0.4064)
			(end -0.7874 -0.4064)
			(stroke
				(width 0.1524)
				(type default)
			)
			(layer "F.SilkS")
		)
		(fp_line
			(start -0.7874 -0.4064)
			(end 0.7874 -0.4064)
			(stroke
				(width 0.1524)
				(type default)
			)
			(layer "F.SilkS")
		)
		(fp_line
			(start 0.67945 0.3048)
			(end 0.120396 0.3048)
			(stroke
				(width 0.1)
				(type default)
			)
			(layer "F.Fab")
		)
		(fp_line
			(start 0.67945 -0.3048)
			(end 0.67945 0.3048)
			(stroke
				(width 0.1)
				(type default)
			)
			(layer "F.Fab")
		)
		(fp_line
			(start 0.12065 -0.2794)
			(end 0.12065 -0.3048)
			(stroke
				(width 0.1)
				(type default)
			)
			(layer "F.Fab")
		)
		(fp_line
			(start 0.12065 -0.3048)
			(end 0.67945 -0.3048)
			(stroke
				(width 0.1)
				(type default)
			)
			(layer "F.Fab")
		)
		(fp_line
			(start 0.120396 0.3048)
			(end 0.120396 0.2794)
			(stroke
				(width 0.1)
				(type default)
			)
			(layer "F.Fab")
		)
		(fp_line
			(start 0.120396 0.2794)
			(end -0.12065 0.2794)
			(stroke
				(width 0.1)
				(type default)
			)
			(layer "F.Fab")
		)
		(fp_line
			(start -0.12065 0.3048)
			(end -0.67945 0.3048)
			(stroke
				(width 0.1)
				(type default)
			)
			(layer "F.Fab")
		)
		(fp_line
			(start -0.12065 0.2794)
			(end -0.12065 0.3048)
			(stroke
				(width 0.1)
				(type default)
			)
			(layer "F.Fab")
		)
		(fp_line
			(start -0.12065 -0.2794)
			(end 0.12065 -0.2794)
			(stroke
				(width 0.1)
				(type default)
			)
			(layer "F.Fab")
		)
		(fp_line
			(start -0.12065 -0.305054)
			(end -0.12065 -0.2794)
			(stroke
				(width 0.1)
				(type default)
			)
			(layer "F.Fab")
		)
		(fp_line
			(start -0.67945 0.3048)
			(end -0.67945 -0.305054)
			(stroke
				(width 0.1)
				(type default)
			)
			(layer "F.Fab")
		)
		(fp_line
			(start -0.67945 -0.305054)
			(end -0.12065 -0.305054)
			(stroke
				(width 0.1)
				(type default)
			)
			(layer "F.Fab")
		)
		(pad "1" smd circle
			(at -0.40005 0 180)
			(size 0 0)
			(layers "F.Cu" "F.Mask" "F.Paste")
			(net "P12V_OCP_SENSE_2")
		)
		(pad "2" smd circle
			(at 0.40005 0 180)
			(size 0 0)
			(layers "F.Cu" "F.Mask" "F.Paste")
			(net "GND")
		)
	)
)
